(kicad_pcb
	(version 20260206)
	(generator "pcbnew")
	(generator_version "10.0")
	(general
		(thickness 1.6)
		(legacy_teardrops no)
	)
	(paper "A4")
	(title_block
		(title "Wiwynn_Tioga_Pass_MB.brd")
		(comment 1 "Tioga Pass / footprints 3675-3682 of 4770")
	)
	(layers
		(0 "F.Cu" signal "TOP")
		(4 "In1.Cu" signal "L2GND")
		(6 "In2.Cu" signal "L3")
		(8 "In3.Cu" signal "L4GND")
		(10 "In4.Cu" signal "L5")
		(12 "In5.Cu" signal "L6GND")
		(14 "In6.Cu" signal "L7VCC")
		(16 "In7.Cu" signal "L8VCC")
		(18 "In8.Cu" signal "L9GND")
		(20 "In9.Cu" signal "L10")
		(22 "In10.Cu" signal "L11GND")
		(24 "In11.Cu" signal "L12")
		(26 "In12.Cu" signal "L13GND")
		(2 "B.Cu" signal "BOTTOM")
		(9 "F.Adhes" user "F.Adhesive")
		(11 "B.Adhes" user "B.Adhesive")
		(13 "F.Paste" user "Package Geometry/Pastemask Top")
		(15 "B.Paste" user "Package Geometry/Pastemask Bottom")
		(5 "F.SilkS" user "Ref Des/Silkscreen Top")
		(7 "B.SilkS" user "Ref Des/Silkscreen Bottom")
		(1 "F.Mask" user "Board Geometry/Soldermask Top")
		(3 "B.Mask" user "Board Geometry/Soldermask Bottom")
		(17 "Dwgs.User" user "User.Drawings")
		(19 "Cmts.User" user "User.Comments")
		(21 "Eco1.User" user "User.Eco1")
		(23 "Eco2.User" user "User.Eco2")
		(25 "Edge.Cuts" user "Board Geometry/Outline")
		(27 "Margin" user)
		(31 "F.CrtYd" user "Package Geometry/Place Bound Top")
		(29 "B.CrtYd" user "Package Geometry/Place Bound Bottom")
		(35 "F.Fab" user "Ref Des/Assembly Top")
		(33 "B.Fab" user "Ref Des/Assembly Bottom")
	)
	(footprint ""
		(layer "B.Cu")
		(at 393.446 -27.686 -90)
		(property "Reference" "C8F16"
			(at 0 0 90)
			(layer "B.SilkS")
			(hide yes)
			(effects
				(font
					(size 1.27 1.27)
				)
				(justify mirror)
			)
		)
		(property "Value" ""
			(at 0 0 90)
			(layer "B.Fab")
			(effects
				(font
					(size 1.27 1.27)
				)
				(justify mirror)
			)
		)
		(duplicate_pad_numbers_are_jumpers no)
		(fp_poly
			(pts
				(xy -0.3048 -0.1016) (xy -0.3048 0.9906) (xy 0.3048 0.9906) (xy 0.3048 -0.1016)
			)
			(stroke
				(width 0)
				(type default)
			)
			(fill no)
			(layer "B.CrtYd")
		)
		(fp_line
			(start -0.3048 0.9906)
			(end -0.3048 -0.1016)
			(stroke
				(width 0.1)
				(type default)
			)
			(layer "B.Fab")
		)
		(fp_line
			(start 0.3048 0.9906)
			(end -0.3048 0.9906)
			(stroke
				(width 0.1)
				(type default)
			)
			(layer "B.Fab")
		)
		(fp_line
			(start -0.3048 -0.1016)
			(end 0.3048 -0.1016)
			(stroke
				(width 0.1)
				(type default)
			)
			(layer "B.Fab")
		)
		(fp_line
			(start 0.3048 -0.1016)
			(end 0.3048 0.9906)
			(stroke
				(width 0.1)
				(type default)
			)
			(layer "B.Fab")
		)
		(pad "1" smd rect
			(at 0 0 90)
			(size 0.508 0.508)
			(layers "B.Cu" "B.Mask" "B.Paste")
			(net "P3V3_STBY")
		)
		(pad "2" smd rect
			(at 0 0.889 90)
			(size 0.508 0.508)
			(layers "B.Cu" "B.Mask" "B.Paste")
			(net "GND")
		)
		(zone
			(layer "B.Cu")
			(hatch none 0.5)
			(connect_pads
				(clearance 0)
			)
			(min_thickness 0.25)
			(keepout
				(tracks not_allowed)
				(vias allowed)
				(pads allowed)
				(copperpour not_allowed)
				(footprints allowed)
			)
			(placement
				(enabled no)
				(sheetname "")
			)
			(fill
				(thermal_gap 0.5)
				(thermal_bridge_width 0.5)
				(island_removal_mode 0)
			)
			(polygon
				(pts
					(xy 392.811 -27.432) (xy 392.811 -27.94) (xy 393.192 -27.94) (xy 393.192 -27.432)
				)
			)
		)
		(zone
			(layer "B.Cu")
			(hatch none 0.5)
			(connect_pads
				(clearance 0)
			)
			(min_thickness 0.25)
			(keepout
				(tracks allowed)
				(vias not_allowed)
				(pads allowed)
				(copperpour not_allowed)
				(footprints allowed)
			)
			(placement
				(enabled no)
				(sheetname "")
			)
			(fill
				(thermal_gap 0.5)
				(thermal_bridge_width 0.5)
				(island_removal_mode 0)
			)
			(polygon
				(pts
					(xy 393.192 -27.432) (xy 393.192 -27.94) (xy 392.811 -27.94) (xy 392.811 -27.432)
				)
			)
		)
	)
	(footprint ""
		(layer "B.Cu")
		(at 391.075926 -36.564316 90)
		(property "Reference" "R8F36"
			(at 0 0 90)
			(layer "B.SilkS")
			(hide yes)
			(effects
				(font
					(size 1.27 1.27)
				)
				(justify mirror)
			)
		)
		(property "Value" ""
			(at 0 0 90)
			(layer "B.Fab")
			(effects
				(font
					(size 1.27 1.27)
				)
				(justify mirror)
			)
		)
		(duplicate_pad_numbers_are_jumpers no)
		(fp_poly
			(pts
				(xy 0.2794 -0.1016) (xy -0.2794 -0.1016) (xy -0.2794 0.9906) (xy 0.2794 0.9906)
			)
			(stroke
				(width 0)
				(type default)
			)
			(fill no)
			(layer "B.CrtYd")
		)
		(fp_line
			(start 0.2794 -0.1016)
			(end 0.2794 0.9906)
			(stroke
				(width 0.1)
				(type default)
			)
			(layer "B.Fab")
		)
		(fp_line
			(start -0.2794 -0.1016)
			(end 0.2794 -0.1016)
			(stroke
				(width 0.1)
				(type default)
			)
			(layer "B.Fab")
		)
		(fp_line
			(start 0.2794 0.9906)
			(end -0.2794 0.9906)
			(stroke
				(width 0.1)
				(type default)
			)
			(layer "B.Fab")
		)
		(fp_line
			(start -0.2794 0.9906)
			(end -0.2794 -0.1016)
			(stroke
				(width 0.1)
				(type default)
			)
			(layer "B.Fab")
		)
		(pad "1" smd rect
			(at 0 0 270)
			(size 0.508 0.508)
			(layers "B.Cu" "B.Mask" "B.Paste")
			(net "P3V3")
		)
		(pad "2" smd rect
			(at 0 0.889 270)
			(size 0.508 0.508)
			(layers "B.Cu" "B.Mask" "B.Paste")
			(net "PU_M2_CLK_REQ_N")
		)
		(zone
			(layer "B.Cu")
			(hatch none 0.5)
			(connect_pads
				(clearance 0)
			)
			(min_thickness 0.25)
			(keepout
				(tracks allowed)
				(vias not_allowed)
				(pads allowed)
				(copperpour not_allowed)
				(footprints allowed)
			)
			(placement
				(enabled no)
				(sheetname "")
			)
			(fill
				(thermal_gap 0.5)
				(thermal_bridge_width 0.5)
				(island_removal_mode 0)
			)
			(polygon
				(pts
					(xy 391.329926 -36.818316) (xy 391.329926 -36.310316) (xy 391.710926 -36.310316) (xy 391.710926 -36.818316)
				)
			)
		)
		(zone
			(layer "B.Cu")
			(hatch none 0.5)
			(connect_pads
				(clearance 0)
			)
			(min_thickness 0.25)
			(keepout
				(tracks not_allowed)
				(vias allowed)
				(pads allowed)
				(copperpour not_allowed)
				(footprints allowed)
			)
			(placement
				(enabled no)
				(sheetname "")
			)
			(fill
				(thermal_gap 0.5)
				(thermal_bridge_width 0.5)
				(island_removal_mode 0)
			)
			(polygon
				(pts
					(xy 391.710926 -36.818316) (xy 391.710926 -36.310316) (xy 391.329926 -36.310316) (xy 391.329926 -36.818316)
				)
			)
		)
	)
	(footprint ""
		(layer "B.Cu")
		(at 476.4786 -41.1734 -90)
		(property "Reference" "C22W35"
			(at 0 0 90)
			(layer "B.SilkS")
			(hide yes)
			(effects
				(font
					(size 1.27 1.27)
				)
				(justify mirror)
			)
		)
		(property "Value" "*"
			(at 0.0762 -6.2357 270)
			(unlocked yes)
			(layer "B.Fab")
			(hide yes)
			(effects
				(font
					(size 1.27 1.016)
					(thickness 0.1524)
				)
				(justify mirror)
			)
		)
		(property "Device Type" "SC22U16V5MX-4-GP_SMD-BCG5-SC22A"
			(at 0.0762 -8.2677 270)
			(unlocked yes)
			(layer "B.Fab")
			(hide yes)
			(effects
				(font
					(size 1.27 1.016)
					(thickness 0.1524)
				)
				(justify mirror)
			)
		)
		(duplicate_pad_numbers_are_jumpers no)
		(fp_line
			(start -0.635 0)
			(end 0.635 0)
			(stroke
				(width 0.508)
				(type default)
			)
			(layer "B.SilkS")
		)
		(fp_rect
			(start 0.9652 1.778)
			(end -0.9652 -1.778)
			(stroke
				(width 0)
				(type default)
			)
			(fill no)
			(layer "B.CrtYd")
		)
		(fp_poly
			(pts
				(xy 0.9652 -1.778) (xy -0.9652 -1.778) (xy -0.9652 1.778) (xy 0.9652 1.778)
			)
			(stroke
				(width 0)
				(type default)
			)
			(fill no)
			(layer "B.Fab")
		)
		(pad "1" smd rect
			(at 0 -0.9652 90)
			(size 1.397 1.143)
			(layers "B.Cu" "B.Mask" "B.Paste")
			(net "P1V5_LAN")
		)
		(pad "2" smd rect
			(at 0 0.9652 90)
			(size 1.397 1.143)
			(layers "B.Cu" "B.Mask" "B.Paste")
			(net "GND")
		)
	)
	(footprint ""
		(layer "B.Cu")
		(at 169.418 -125.603 90)
		(property "Reference" "R6M8"
			(at 0 0 90)
			(layer "B.SilkS")
			(hide yes)
			(effects
				(font
					(size 1.27 1.27)
				)
				(justify mirror)
			)
		)
		(property "Value" ""
			(at 0 0 90)
			(layer "B.Fab")
			(effects
				(font
					(size 1.27 1.27)
				)
				(justify mirror)
			)
		)
		(duplicate_pad_numbers_are_jumpers no)
		(fp_rect
			(start -0.2794 0.9906)
			(end 0.2794 -0.1016)
			(stroke
				(width 0)
				(type default)
			)
			(fill no)
			(layer "B.CrtYd")
		)
		(fp_line
			(start 0.2794 -0.1016)
			(end 0.2794 0.9906)
			(stroke
				(width 0.1)
				(type default)
			)
			(layer "B.Fab")
		)
		(fp_line
			(start -0.2794 -0.1016)
			(end 0.2794 -0.1016)
			(stroke
				(width 0.1)
				(type default)
			)
			(layer "B.Fab")
		)
		(fp_line
			(start 0.2794 0.9906)
			(end -0.2794 0.9906)
			(stroke
				(width 0.1)
				(type default)
			)
			(layer "B.Fab")
		)
		(fp_line
			(start -0.2794 0.9906)
			(end -0.2794 -0.1016)
			(stroke
				(width 0.1)
				(type default)
			)
			(layer "B.Fab")
		)
		(pad "1" smd rect
			(at 0 0 270)
			(size 0.508 0.508)
			(layers "B.Cu" "B.Mask" "B.Paste")
			(net "JTAG_MCP_CPU1_TDI_R")
		)
		(pad "2" smd rect
			(at 0 0.889 270)
			(size 0.508 0.508)
			(layers "B.Cu" "B.Mask" "B.Paste")
			(net "JTAG_MCP_CPU1_TDI")
		)
		(zone
			(layer "B.Cu")
			(hatch none 0.5)
			(connect_pads
				(clearance 0)
			)
			(min_thickness 0.25)
			(keepout
				(tracks allowed)
				(vias not_allowed)
				(pads allowed)
				(copperpour not_allowed)
				(footprints allowed)
			)
			(placement
				(enabled no)
				(sheetname "")
			)
			(fill
				(thermal_gap 0.5)
				(thermal_bridge_width 0.5)
				(island_removal_mode 0)
			)
			(polygon
				(pts
					(xy 170.053 -125.349) (xy 170.053 -125.857) (xy 169.672 -125.857) (xy 169.672 -125.349)
				)
			)
		)
		(zone
			(layer "B.Cu")
			(hatch none 0.5)
			(connect_pads
				(clearance 0)
			)
			(min_thickness 0.25)
			(keepout
				(tracks not_allowed)
				(vias allowed)
				(pads allowed)
				(copperpour not_allowed)
				(footprints allowed)
			)
			(placement
				(enabled no)
				(sheetname "")
			)
			(fill
				(thermal_gap 0.5)
				(thermal_bridge_width 0.5)
				(island_removal_mode 0)
			)
			(polygon
				(pts
					(xy 170.053 -125.349) (xy 170.053 -125.857) (xy 169.672 -125.857) (xy 169.672 -125.349)
				)
			)
		)
	)
	(footprint ""
		(layer "B.Cu")
		(at 193.092832 -17.723612 -90)
		(property "Reference" "C6T2"
			(at 0 0 90)
			(layer "B.SilkS")
			(hide yes)
			(effects
				(font
					(size 1.27 1.27)
				)
				(justify mirror)
			)
		)
		(property "Value" ""
			(at 0 0 90)
			(layer "B.Fab")
			(effects
				(font
					(size 1.27 1.27)
				)
				(justify mirror)
			)
		)
		(duplicate_pad_numbers_are_jumpers no)
		(fp_rect
			(start 0.7239 1.9939)
			(end -0.7239 -0.2159)
			(stroke
				(width 0)
				(type default)
			)
			(fill no)
			(layer "B.CrtYd")
		)
		(fp_line
			(start -0.7239 1.9939)
			(end -0.7239 -0.2159)
			(stroke
				(width 0.1)
				(type default)
			)
			(layer "B.Fab")
		)
		(fp_line
			(start 0.7239 1.9939)
			(end -0.7239 1.9939)
			(stroke
				(width 0.1)
				(type default)
			)
			(layer "B.Fab")
		)
		(fp_line
			(start -0.7239 -0.2159)
			(end 0.7239 -0.2159)
			(stroke
				(width 0.1)
				(type default)
			)
			(layer "B.Fab")
		)
		(fp_line
			(start 0.7239 -0.2159)
			(end 0.7239 1.9939)
			(stroke
				(width 0.1)
				(type default)
			)
			(layer "B.Fab")
		)
		(pad "1" smd rect
			(at 0 0 90)
			(size 1.27 1.016)
			(layers "B.Cu" "B.Mask" "B.Paste")
			(net "P12V_NVDIMM_ABC")
		)
		(pad "2" smd rect
			(at 0 1.778 90)
			(size 1.27 1.016)
			(layers "B.Cu" "B.Mask" "B.Paste")
			(net "GND")
		)
		(zone
			(layer "B.Cu")
			(hatch none 0.5)
			(connect_pads
				(clearance 0)
			)
			(min_thickness 0.25)
			(keepout
				(tracks not_allowed)
				(vias allowed)
				(pads allowed)
				(copperpour not_allowed)
				(footprints allowed)
			)
			(placement
				(enabled no)
				(sheetname "")
			)
			(fill
				(thermal_gap 0.5)
				(thermal_bridge_width 0.5)
				(island_removal_mode 0)
			)
			(polygon
				(pts
					(xy 191.822832 -17.088612) (xy 192.584832 -17.088612) (xy 192.584832 -18.358612) (xy 191.822832 -18.358612)
				)
			)
		)
	)
	(footprint ""
		(layer "B.Cu")
		(at 94.638368 1.47574 90)
		(property "Reference" "C8U10"
			(at -1.47828 0.78994 180)
			(unlocked yes)
			(layer "B.SilkS")
			(effects
				(font
					(size 0.4064 0.254)
					(thickness 0.1524)
				)
				(justify mirror)
			)
		)
		(property "Value" ""
			(at 0 0 90)
			(layer "B.Fab")
			(effects
				(font
					(size 1.27 1.27)
				)
				(justify mirror)
			)
		)
		(duplicate_pad_numbers_are_jumpers no)
		(fp_poly
			(pts
				(xy 0.7239 -0.2159) (xy -0.7239 -0.2159) (xy -0.7239 1.9939) (xy 0.7239 1.9939)
			)
			(stroke
				(width 0)
				(type default)
			)
			(fill no)
			(layer "B.CrtYd")
		)
		(fp_line
			(start 0.7239 -0.2159)
			(end 0.7239 1.9939)
			(stroke
				(width 0.1)
				(type default)
			)
			(layer "B.Fab")
		)
		(fp_line
			(start -0.7239 -0.2159)
			(end 0.7239 -0.2159)
			(stroke
				(width 0.1)
				(type default)
			)
			(layer "B.Fab")
		)
		(fp_line
			(start 0.7239 1.9939)
			(end -0.7239 1.9939)
			(stroke
				(width 0.1)
				(type default)
			)
			(layer "B.Fab")
		)
		(fp_line
			(start -0.7239 1.9939)
			(end -0.7239 -0.2159)
			(stroke
				(width 0.1)
				(type default)
			)
			(layer "B.Fab")
		)
		(pad "1" smd rect
			(at 0 0 270)
			(size 1.27 1.016)
			(layers "B.Cu" "B.Mask" "B.Paste")
			(net "PVTT_GHJ")
		)
		(pad "2" smd rect
			(at 0 1.778 270)
			(size 1.27 1.016)
			(layers "B.Cu" "B.Mask" "B.Paste")
			(net "GND")
		)
		(zone
			(layer "B.Cu")
			(hatch none 0.5)
			(connect_pads
				(clearance 0)
			)
			(min_thickness 0.25)
			(keepout
				(tracks not_allowed)
				(vias allowed)
				(pads allowed)
				(copperpour not_allowed)
				(footprints allowed)
			)
			(placement
				(enabled no)
				(sheetname "")
			)
			(fill
				(thermal_gap 0.5)
				(thermal_bridge_width 0.5)
				(island_removal_mode 0)
			)
			(polygon
				(pts
					(xy 95.146368 0.84074) (xy 95.146368 2.11074) (xy 95.908368 2.11074) (xy 95.908368 0.84074)
				)
			)
		)
	)
	(footprint ""
		(layer "B.Cu")
		(at 351.507806 -61.257434)
		(property "Reference" "C2U16"
			(at 0 0 0)
			(layer "B.SilkS")
			(hide yes)
			(effects
				(font
					(size 1.27 1.27)
				)
				(justify mirror)
			)
		)
		(property "Value" ""
			(at 0 0 0)
			(layer "B.Fab")
			(effects
				(font
					(size 1.27 1.27)
				)
				(justify mirror)
			)
		)
		(duplicate_pad_numbers_are_jumpers no)
		(fp_poly
			(pts
				(xy -0.3048 -0.1016) (xy -0.3048 0.9906) (xy 0.3048 0.9906) (xy 0.3048 -0.1016)
			)
			(stroke
				(width 0)
				(type default)
			)
			(fill no)
			(layer "B.CrtYd")
		)
		(fp_line
			(start -0.3048 -0.1016)
			(end 0.3048 -0.1016)
			(stroke
				(width 0.1)
				(type default)
			)
			(layer "B.Fab")
		)
		(fp_line
			(start -0.3048 0.9906)
			(end -0.3048 -0.1016)
			(stroke
				(width 0.1)
				(type default)
			)
			(layer "B.Fab")
		)
		(fp_line
			(start 0.3048 -0.1016)
			(end 0.3048 0.9906)
			(stroke
				(width 0.1)
				(type default)
			)
			(layer "B.Fab")
		)
		(fp_line
			(start 0.3048 0.9906)
			(end -0.3048 0.9906)
			(stroke
				(width 0.1)
				(type default)
			)
			(layer "B.Fab")
		)
		(pad "1" smd rect
			(at 0 0 180)
			(size 0.508 0.508)
			(layers "B.Cu" "B.Mask" "B.Paste")
			(net "P3E_CPU0_PE1_PCH_RXN<6>")
		)
		(pad "2" smd rect
			(at 0 0.889 180)
			(size 0.508 0.508)
			(layers "B.Cu" "B.Mask" "B.Paste")
			(net "P3E_CPU0_PE1_SS_RXN<6>")
		)
		(zone
			(layer "B.Cu")
			(hatch none 0.5)
			(connect_pads
				(clearance 0)
			)
			(min_thickness 0.25)
			(keepout
				(tracks allowed)
				(vias not_allowed)
				(pads allowed)
				(copperpour not_allowed)
				(footprints allowed)
			)
			(placement
				(enabled no)
				(sheetname "")
			)
			(fill
				(thermal_gap 0.5)
				(thermal_bridge_width 0.5)
				(island_removal_mode 0)
			)
			(polygon
				(pts
					(xy 351.761806 -61.003434) (xy 351.253806 -61.003434) (xy 351.253806 -60.622434) (xy 351.761806 -60.622434)
				)
			)
		)
		(zone
			(layer "B.Cu")
			(hatch none 0.5)
			(connect_pads
				(clearance 0)
			)
			(min_thickness 0.25)
			(keepout
				(tracks not_allowed)
				(vias allowed)
				(pads allowed)
				(copperpour not_allowed)
				(footprints allowed)
			)
			(placement
				(enabled no)
				(sheetname "")
			)
			(fill
				(thermal_gap 0.5)
				(thermal_bridge_width 0.5)
				(island_removal_mode 0)
			)
			(polygon
				(pts
					(xy 351.761806 -60.622434) (xy 351.253806 -60.622434) (xy 351.253806 -61.003434) (xy 351.761806 -61.003434)
				)
			)
		)
	)
	(footprint ""
		(layer "B.Cu")
		(at 470.379044 -4.56692 -90)
		(property "Reference" "C2U24"
			(at 0 0 90)
			(layer "B.SilkS")
			(hide yes)
			(effects
				(font
					(size 1.27 1.27)
				)
				(justify mirror)
			)
		)
		(property "Value" ""
			(at 0 0 90)
			(layer "B.Fab")
			(effects
				(font
					(size 1.27 1.27)
				)
				(justify mirror)
			)
		)
		(duplicate_pad_numbers_are_jumpers no)
		(fp_poly
			(pts
				(xy -0.3048 -0.1016) (xy -0.3048 0.9906) (xy 0.3048 0.9906) (xy 0.3048 -0.1016)
			)
			(stroke
				(width 0)
				(type default)
			)
			(fill no)
			(layer "B.CrtYd")
		)
		(fp_line
			(start -0.3048 0.9906)
			(end -0.3048 -0.1016)
			(stroke
				(width 0.1)
				(type default)
			)
			(layer "B.Fab")
		)
		(fp_line
			(start 0.3048 0.9906)
			(end -0.3048 0.9906)
			(stroke
				(width 0.1)
				(type default)
			)
			(layer "B.Fab")
		)
		(fp_line
			(start -0.3048 -0.1016)
			(end 0.3048 -0.1016)
			(stroke
				(width 0.1)
				(type default)
			)
			(layer "B.Fab")
		)
		(fp_line
			(start 0.3048 -0.1016)
			(end 0.3048 0.9906)
			(stroke
				(width 0.1)
				(type default)
			)
			(layer "B.Fab")
		)
		(pad "1" smd rect
			(at 0 0 90)
			(size 0.508 0.508)
			(layers "B.Cu" "B.Mask" "B.Paste")
			(net "P12V")
		)
		(pad "2" smd rect
			(at 0 0.889 90)
			(size 0.508 0.508)
			(layers "B.Cu" "B.Mask" "B.Paste")
			(net "GND")
		)
		(zone
			(layer "B.Cu")
			(hatch none 0.5)
			(connect_pads
				(clearance 0)
			)
			(min_thickness 0.25)
			(keepout
				(tracks not_allowed)
				(vias allowed)
				(pads allowed)
				(copperpour not_allowed)
				(footprints allowed)
			)
			(placement
				(enabled no)
				(sheetname "")
			)
			(fill
				(thermal_gap 0.5)
				(thermal_bridge_width 0.5)
				(island_removal_mode 0)
			)
			(polygon
				(pts
					(xy 469.744044 -4.31292) (xy 469.744044 -4.82092) (xy 470.125044 -4.82092) (xy 470.125044 -4.31292)
				)
			)
		)
		(zone
			(layer "B.Cu")
			(hatch none 0.5)
			(connect_pads
				(clearance 0)
			)
			(min_thickness 0.25)
			(keepout
				(tracks allowed)
				(vias not_allowed)
				(pads allowed)
				(copperpour not_allowed)
				(footprints allowed)
			)
			(placement
				(enabled no)
				(sheetname "")
			)
			(fill
				(thermal_gap 0.5)
				(thermal_bridge_width 0.5)
				(island_removal_mode 0)
			)
			(polygon
				(pts
					(xy 470.125044 -4.31292) (xy 470.125044 -4.82092) (xy 469.744044 -4.82092) (xy 469.744044 -4.31292)
				)
			)
		)
	)
)
